# T6G (Grand Teton) — schematic netlist excerpt (pin names and nets, part order shuffled) for the footprints in the layout excerpt that follows; sources: Cadence DE-HDL packaged netlist, KiCad conversion of 04192023_DAF0TMB3IC0_F0TG_MB_C_brd_V02_OCP.brd

C1081  Q_CAP  100PF 50V 5% EMPTY  pkg 0402  page 258 : A = PVDD18_S5_P1_ADC_MAM ; B = GND
R443  Q_RES  1K 1% CHIP  pkg 0402LF  page 28 : A = PWRGD_CPU0_PWROK ; B = PVDD18_S5_P0

(kicad_pcb
	(version 20260206)
	(generator "pcbnew")
	(generator_version "10.0")
	(general
		(thickness 1.6)
		(legacy_teardrops no)
	)
	(paper "A4")
	(title_block
		(title "04192023_DAF0TMB3IC0_F0TG_MB_C_brd_V02_OCP.brd")
		(comment 1 "Grand Teton / footprints 6365-6366 of 8354")
	)
	(layers
		(0 "F.Cu" signal "TOP")
		(4 "In1.Cu" signal "GND")
		(6 "In2.Cu" signal "IN1")
		(8 "In3.Cu" signal "GND1")
		(10 "In4.Cu" signal "IN2")
		(12 "In5.Cu" signal "GND2")
		(14 "In6.Cu" signal "IN3")
		(16 "In7.Cu" signal "GND3")
		(18 "In8.Cu" signal "VCC")
		(20 "In9.Cu" signal "VCC1")
		(22 "In10.Cu" signal "GND4")
		(24 "In11.Cu" signal "IN4")
		(26 "In12.Cu" signal "GND5")
		(28 "In13.Cu" signal "IN5")
		(30 "In14.Cu" signal "GND6")
		(32 "In15.Cu" signal "IN6")
		(34 "In16.Cu" signal "GND7")
		(2 "B.Cu" signal "BOTTOM")
		(9 "F.Adhes" user "F.Adhesive")
		(11 "B.Adhes" user "B.Adhesive")
		(13 "F.Paste" user "Package Geometry/Pastemask Top")
		(15 "B.Paste" user "Package Geometry/Pastemask Bottom")
		(5 "F.SilkS" user "Ref Des/Silkscreen Top")
		(7 "B.SilkS" user "Ref Des/Silkscreen Bottom")
		(1 "F.Mask" user "Board Geometry/Soldermask Top")
		(3 "B.Mask" user "Board Geometry/Soldermask Bottom")
		(17 "Dwgs.User" user "User.Drawings")
		(19 "Cmts.User" user "User.Comments")
		(21 "Eco1.User" user "User.Eco1")
		(23 "Eco2.User" user "User.Eco2")
		(25 "Edge.Cuts" user "Board Geometry/Outline")
		(27 "Margin" user)
		(31 "F.CrtYd" user "Package Geometry/Place Bound Top")
		(29 "B.CrtYd" user "Package Geometry/Place Bound Bottom")
		(35 "F.Fab" user "Ref Des/Assembly Top")
		(33 "B.Fab" user "Ref Des/Assembly Bottom")
	)
	(footprint ""
		(layer "B.Cu")
		(at 243.713 -324.866)
		(property "Reference" "C1081"
			(at 0 0 0)
			(layer "B.SilkS")
			(hide yes)
			(effects
				(font
					(size 1.27 1.27)
				)
				(justify mirror)
			)
		)
		(property "Value" ""
			(at 0 0 0)
			(layer "B.Fab")
			(effects
				(font
					(size 1.27 1.27)
				)
				(justify mirror)
			)
		)
		(duplicate_pad_numbers_are_jumpers no)
		(fp_line
			(start -0.7874 -0.4064)
			(end -0.7874 0.4064)
			(stroke
				(width 0.1524)
				(type default)
			)
			(layer "B.SilkS")
		)
		(fp_line
			(start -0.7874 0.4064)
			(end 0.7874 0.4064)
			(stroke
				(width 0.1524)
				(type default)
			)
			(layer "B.SilkS")
		)
		(fp_line
			(start 0.7874 -0.4064)
			(end -0.7874 -0.4064)
			(stroke
				(width 0.1524)
				(type default)
			)
			(layer "B.SilkS")
		)
		(fp_line
			(start 0.7874 0.4064)
			(end 0.7874 -0.4064)
			(stroke
				(width 0.1524)
				(type default)
			)
			(layer "B.SilkS")
		)
		(fp_line
			(start -0.67945 -0.3048)
			(end -0.67945 0.3048)
			(stroke
				(width 0.1)
				(type default)
			)
			(layer "B.Fab")
		)
		(fp_line
			(start -0.67945 0.3048)
			(end -0.120396 0.3048)
			(stroke
				(width 0.1)
				(type default)
			)
			(layer "B.Fab")
		)
		(fp_line
			(start -0.12065 -0.3048)
			(end -0.67945 -0.3048)
			(stroke
				(width 0.1)
				(type default)
			)
			(layer "B.Fab")
		)
		(fp_line
			(start -0.12065 -0.2794)
			(end -0.12065 -0.3048)
			(stroke
				(width 0.1)
				(type default)
			)
			(layer "B.Fab")
		)
		(fp_line
			(start -0.120396 0.2794)
			(end 0.12065 0.2794)
			(stroke
				(width 0.1)
				(type default)
			)
			(layer "B.Fab")
		)
		(fp_line
			(start -0.120396 0.3048)
			(end -0.120396 0.2794)
			(stroke
				(width 0.1)
				(type default)
			)
			(layer "B.Fab")
		)
		(fp_line
			(start 0.12065 -0.305054)
			(end 0.12065 -0.2794)
			(stroke
				(width 0.1)
				(type default)
			)
			(layer "B.Fab")
		)
		(fp_line
			(start 0.12065 -0.2794)
			(end -0.12065 -0.2794)
			(stroke
				(width 0.1)
				(type default)
			)
			(layer "B.Fab")
		)
		(fp_line
			(start 0.12065 0.2794)
			(end 0.12065 0.3048)
			(stroke
				(width 0.1)
				(type default)
			)
			(layer "B.Fab")
		)
		(fp_line
			(start 0.12065 0.3048)
			(end 0.67945 0.3048)
			(stroke
				(width 0.1)
				(type default)
			)
			(layer "B.Fab")
		)
		(fp_line
			(start 0.67945 -0.305054)
			(end 0.12065 -0.305054)
			(stroke
				(width 0.1)
				(type default)
			)
			(layer "B.Fab")
		)
		(fp_line
			(start 0.67945 0.3048)
			(end 0.67945 -0.305054)
			(stroke
				(width 0.1)
				(type default)
			)
			(layer "B.Fab")
		)
		(pad "1" smd circle
			(at 0.40005 0 180)
			(size 0 0)
			(layers "B.Cu" "B.Mask" "B.Paste")
			(net "PVDD18_S5_P1_ADC_MAM")
		)
		(pad "2" smd circle
			(at -0.40005 0 180)
			(size 0 0)
			(layers "B.Cu" "B.Mask" "B.Paste")
			(net "GND")
		)
	)
	(footprint ""
		(layer "B.Cu")
		(at 320.211958 -203.917296 90)
		(property "Reference" "R443"
			(at 0 0 90)
			(layer "B.SilkS")
			(hide yes)
			(effects
				(font
					(size 1.27 1.27)
				)
				(justify mirror)
			)
		)
		(property "Value" ""
			(at 0 0 90)
			(layer "B.Fab")
			(effects
				(font
					(size 1.27 1.27)
				)
				(justify mirror)
			)
		)
		(duplicate_pad_numbers_are_jumpers no)
		(fp_line
			(start 0.7874 -0.4064)
			(end -0.7874 -0.4064)
			(stroke
				(width 0.1524)
				(type default)
			)
			(layer "B.SilkS")
		)
		(fp_line
			(start -0.7874 -0.4064)
			(end -0.7874 0.4064)
			(stroke
				(width 0.1524)
				(type default)
			)
			(layer "B.SilkS")
		)
		(fp_line
			(start 0.7874 0.4064)
			(end 0.7874 -0.4064)
			(stroke
				(width 0.1524)
				(type default)
			)
			(layer "B.SilkS")
		)
		(fp_line
			(start -0.7874 0.4064)
			(end 0.7874 0.4064)
			(stroke
				(width 0.1524)
				(type default)
			)
			(layer "B.SilkS")
		)
		(fp_line
			(start 0.67945 -0.305054)
			(end 0.12065 -0.305054)
			(stroke
				(width 0.1)
				(type default)
			)
			(layer "B.Fab")
		)
		(fp_line
			(start 0.12065 -0.305054)
			(end 0.12065 -0.2794)
			(stroke
				(width 0.1)
				(type default)
			)
			(layer "B.Fab")
		)
		(fp_line
			(start -0.12065 -0.3048)
			(end -0.67945 -0.3048)
			(stroke
				(width 0.1)
				(type default)
			)
			(layer "B.Fab")
		)
		(fp_line
			(start -0.67945 -0.3048)
			(end -0.67945 0.3048)
			(stroke
				(width 0.1)
				(type default)
			)
			(layer "B.Fab")
		)
		(fp_line
			(start 0.12065 -0.2794)
			(end -0.12065 -0.2794)
			(stroke
				(width 0.1)
				(type default)
			)
			(layer "B.Fab")
		)
		(fp_line
			(start -0.12065 -0.2794)
			(end -0.12065 -0.3048)
			(stroke
				(width 0.1)
				(type default)
			)
			(layer "B.Fab")
		)
		(fp_line
			(start 0.12065 0.2794)
			(end 0.12065 0.3048)
			(stroke
				(width 0.1)
				(type default)
			)
			(layer "B.Fab")
		)
		(fp_line
			(start -0.120396 0.2794)
			(end 0.12065 0.2794)
			(stroke
				(width 0.1)
				(type default)
			)
			(layer "B.Fab")
		)
		(fp_line
			(start 0.67945 0.3048)
			(end 0.67945 -0.305054)
			(stroke
				(width 0.1)
				(type default)
			)
			(layer "B.Fab")
		)
		(fp_line
			(start 0.12065 0.3048)
			(end 0.67945 0.3048)
			(stroke
				(width 0.1)
				(type default)
			)
			(layer "B.Fab")
		)
		(fp_line
			(start -0.120396 0.3048)
			(end -0.120396 0.2794)
			(stroke
				(width 0.1)
				(type default)
			)
			(layer "B.Fab")
		)
		(fp_line
			(start -0.67945 0.3048)
			(end -0.120396 0.3048)
			(stroke
				(width 0.1)
				(type default)
			)
			(layer "B.Fab")
		)
		(pad "1" smd circle
			(at 0.40005 0 270)
			(size 0 0)
			(layers "B.Cu" "B.Mask" "B.Paste")
			(net "PWRGD_CPU0_PWROK")
		)
		(pad "2" smd circle
			(at -0.40005 0 270)
			(size 0 0)
			(layers "B.Cu" "B.Mask" "B.Paste")
			(net "PVDD18_S5_P0")
		)
	)
)
